(kicad_pcb
	(version 20260206)
	(generator "pcbnew")
	(generator_version "10.0")
	(general
		(thickness 1.6)
		(legacy_teardrops no)
	)
	(paper "A4")
	(title_block
		(title "Bryce Canyon_Front Panel_16369-1_OCP.brd")
		(comment 1 "Bryce Canyon / footprints 74-80 of 154")
	)
	(layers
		(0 "F.Cu" signal "TOP")
		(4 "In1.Cu" signal "L2GND")
		(6 "In2.Cu" signal "L3VCC")
		(2 "B.Cu" signal "BOTTOM")
		(9 "F.Adhes" user "F.Adhesive")
		(11 "B.Adhes" user "B.Adhesive")
		(13 "F.Paste" user "Package Geometry/Pastemask Top")
		(15 "B.Paste" user "Package Geometry/Pastemask Bottom")
		(5 "F.SilkS" user "Ref Des/Silkscreen Top")
		(7 "B.SilkS" user "Ref Des/Silkscreen Bottom")
		(1 "F.Mask" user "Board Geometry/Soldermask Top")
		(3 "B.Mask" user "Board Geometry/Soldermask Bottom")
		(17 "Dwgs.User" user "User.Drawings")
		(19 "Cmts.User" user "User.Comments")
		(21 "Eco1.User" user "User.Eco1")
		(23 "Eco2.User" user "User.Eco2")
		(25 "Edge.Cuts" user "Board Geometry/Outline")
		(27 "Margin" user)
		(31 "F.CrtYd" user "Package Geometry/Place Bound Top")
		(29 "B.CrtYd" user "Package Geometry/Place Bound Bottom")
		(35 "F.Fab" user "Ref Des/Assembly Top")
		(33 "B.Fab" user "Ref Des/Assembly Bottom")
	)
	(footprint ""
		(layer "F.Cu")
		(at 12.2682 -44.1452)
		(property "Reference" "R29"
			(at 0 0 0)
			(layer "F.SilkS")
			(hide yes)
			(effects
				(font
					(size 1.27 1.27)
				)
			)
		)
		(property "Value" "4K7R2F-GP"
			(at 0.064008 -4.679696 0)
			(unlocked yes)
			(layer "F.Fab")
			(hide yes)
			(effects
				(font
					(size 2.54 2.54)
					(thickness 0.381)
				)
			)
		)
		(property "Device Type" "R402H16"
			(at 0.064008 -6.203696 0)
			(unlocked yes)
			(layer "F.Fab")
			(hide yes)
			(effects
				(font
					(size 2.54 2.54)
					(thickness 0.381)
				)
			)
		)
		(duplicate_pad_numbers_are_jumpers no)
		(fp_line
			(start -0.508 -0.9398)
			(end -0.508 0.9398)
			(stroke
				(width 0.1524)
				(type default)
			)
			(layer "F.SilkS")
		)
		(fp_line
			(start 0.508 -0.9398)
			(end -0.508 -0.9398)
			(stroke
				(width 0.1524)
				(type default)
			)
			(layer "F.SilkS")
		)
		(fp_rect
			(start -0.508 0.9398)
			(end 0.508 -0.9398)
			(stroke
				(width 0)
				(type default)
			)
			(fill no)
			(layer "F.CrtYd")
		)
		(fp_rect
			(start -0.508 0.9398)
			(end 0.508 -0.9398)
			(stroke
				(width 0)
				(type default)
			)
			(fill no)
			(layer "F.Fab")
		)
		(pad "1" smd custom
			(at 0 -0.4445)
			(size 0.1397 0.1397)
			(layers "F.Cu" "F.Mask" "F.Paste")
			(net "TEMP_1_A2")
			(options
				(clearance outline)
				(anchor circle)
			)
			(primitives
				(gr_poly
					(pts
						(arc
							(start -0.1778 -0.2794)
							(mid -0.249642 -0.249642)
							(end -0.2794 -0.1778)
						)
						(arc
							(start -0.2794 0.1778)
							(mid -0.249642 0.249642)
							(end -0.1778 0.2794)
						)
						(arc
							(start 0.1778 0.2794)
							(mid 0.249642 0.249642)
							(end 0.2794 0.1778)
						)
						(arc
							(start 0.2794 -0.1778)
							(mid 0.249642 -0.249642)
							(end 0.1778 -0.2794)
						)
					)
					(width 0)
					(fill yes)
				)
			)
		)
		(pad "2" smd custom
			(at 0 0.4445)
			(size 0.1397 0.1397)
			(layers "F.Cu" "F.Mask" "F.Paste")
			(net "GND")
			(options
				(clearance outline)
				(anchor circle)
			)
			(primitives
				(gr_poly
					(pts
						(arc
							(start -0.1778 -0.2794)
							(mid -0.249642 -0.249642)
							(end -0.2794 -0.1778)
						)
						(arc
							(start -0.2794 0.1778)
							(mid -0.249642 0.249642)
							(end -0.1778 0.2794)
						)
						(arc
							(start 0.1778 0.2794)
							(mid 0.249642 0.249642)
							(end 0.2794 0.1778)
						)
						(arc
							(start 0.2794 -0.1778)
							(mid 0.249642 -0.249642)
							(end 0.1778 -0.2794)
						)
					)
					(width 0)
					(fill yes)
				)
			)
		)
	)
	(footprint ""
		(layer "F.Cu")
		(at 47.371 -17.8308 -90)
		(property "Reference" "R57"
			(at 0 0 270)
			(layer "F.SilkS")
			(hide yes)
			(effects
				(font
					(size 1.27 1.27)
				)
			)
		)
		(property "Value" "20KR2F-L-GP"
			(at 0.064008 -3.993896 270)
			(unlocked yes)
			(layer "F.Fab")
			(hide yes)
			(effects
				(font
					(size 1.016 1.016)
					(thickness 0.1524)
				)
			)
		)
		(property "Device Type" "R402H16"
			(at 0.064008 -5.517896 270)
			(unlocked yes)
			(layer "F.Fab")
			(hide yes)
			(effects
				(font
					(size 1.016 1.016)
					(thickness 0.1524)
				)
			)
		)
		(duplicate_pad_numbers_are_jumpers no)
		(fp_line
			(start -0.508 -0.9398)
			(end -0.508 0.9398)
			(stroke
				(width 0.1524)
				(type default)
			)
			(layer "F.SilkS")
		)
		(fp_line
			(start 0.508 -0.9398)
			(end -0.508 -0.9398)
			(stroke
				(width 0.1524)
				(type default)
			)
			(layer "F.SilkS")
		)
		(fp_rect
			(start -0.508 0.9398)
			(end 0.508 -0.9398)
			(stroke
				(width 0)
				(type default)
			)
			(fill no)
			(layer "F.CrtYd")
		)
		(fp_rect
			(start -0.508 0.9398)
			(end 0.508 -0.9398)
			(stroke
				(width 0)
				(type default)
			)
			(fill no)
			(layer "F.Fab")
		)
		(pad "1" smd custom
			(at 0 -0.4445 270)
			(size 0.1397 0.1397)
			(layers "F.Cu" "F.Mask" "F.Paste")
			(net "P3V3_STBY_B")
			(options
				(clearance outline)
				(anchor circle)
			)
			(primitives
				(gr_poly
					(pts
						(arc
							(start -0.1778 -0.2794)
							(mid -0.249642 -0.249642)
							(end -0.2794 -0.1778)
						)
						(arc
							(start -0.2794 0.1778)
							(mid -0.249642 0.249642)
							(end -0.1778 0.2794)
						)
						(arc
							(start 0.1778 0.2794)
							(mid 0.249642 0.249642)
							(end 0.2794 0.1778)
						)
						(arc
							(start 0.2794 -0.1778)
							(mid 0.249642 -0.249642)
							(end 0.1778 -0.2794)
						)
					)
					(width 0)
					(fill yes)
				)
			)
		)
		(pad "2" smd custom
			(at 0 0.4445 270)
			(size 0.1397 0.1397)
			(layers "F.Cu" "F.Mask" "F.Paste")
			(net "I2C_DEBUG_B_SDA_L")
			(options
				(clearance outline)
				(anchor circle)
			)
			(primitives
				(gr_poly
					(pts
						(arc
							(start -0.1778 -0.2794)
							(mid -0.249642 -0.249642)
							(end -0.2794 -0.1778)
						)
						(arc
							(start -0.2794 0.1778)
							(mid -0.249642 0.249642)
							(end -0.1778 0.2794)
						)
						(arc
							(start 0.1778 0.2794)
							(mid 0.249642 0.249642)
							(end 0.2794 0.1778)
						)
						(arc
							(start 0.2794 -0.1778)
							(mid 0.249642 -0.249642)
							(end 0.1778 -0.2794)
						)
					)
					(width 0)
					(fill yes)
				)
			)
		)
	)
	(footprint ""
		(layer "F.Cu")
		(at 54.0258 -51.2826 -90)
		(property "Reference" "C15"
			(at 0 0 270)
			(layer "F.SilkS")
			(hide yes)
			(effects
				(font
					(size 1.27 1.27)
				)
			)
		)
		(property "Value" "SCD1U16V2KX-3GP"
			(at 1.1811 -3.3909 270)
			(unlocked yes)
			(layer "F.Fab")
			(hide yes)
			(effects
				(font
					(size 2.54 2.54)
					(thickness 0.381)
				)
			)
		)
		(property "Device Type" "C402H22"
			(at 1.1811 -4.9149 270)
			(unlocked yes)
			(layer "F.Fab")
			(hide yes)
			(effects
				(font
					(size 2.54 2.54)
					(thickness 0.381)
				)
			)
		)
		(duplicate_pad_numbers_are_jumpers no)
		(fp_rect
			(start -0.4318 0.9525)
			(end 0.4318 -0.9525)
			(stroke
				(width 0)
				(type default)
			)
			(fill no)
			(layer "F.CrtYd")
		)
		(fp_rect
			(start -0.4318 0.9525)
			(end 0.4318 -0.9525)
			(stroke
				(width 0)
				(type default)
			)
			(fill no)
			(layer "F.Fab")
		)
		(pad "1" smd custom
			(at 0 -0.4445 270)
			(size 0.1524 0.1524)
			(layers "F.Cu" "F.Mask" "F.Paste")
			(net "P3V3_STBY_B")
			(options
				(clearance outline)
				(anchor circle)
			)
			(primitives
				(gr_poly
					(pts
						(arc
							(start 0.3048 -0.2032)
							(mid 0.275042 -0.275042)
							(end 0.2032 -0.3048)
						)
						(arc
							(start -0.2032 -0.3048)
							(mid -0.275042 -0.275042)
							(end -0.3048 -0.2032)
						)
						(arc
							(start -0.3048 0.2032)
							(mid -0.275042 0.275042)
							(end -0.2032 0.3048)
						)
						(arc
							(start 0.2032 0.3048)
							(mid 0.275042 0.275042)
							(end 0.3048 0.2032)
						)
					)
					(width 0)
					(fill yes)
				)
			)
		)
		(pad "2" smd custom
			(at 0 0.4445 270)
			(size 0.1524 0.1524)
			(layers "F.Cu" "F.Mask" "F.Paste")
			(net "GND")
			(options
				(clearance outline)
				(anchor circle)
			)
			(primitives
				(gr_poly
					(pts
						(arc
							(start 0.3048 -0.2032)
							(mid 0.275042 -0.275042)
							(end 0.2032 -0.3048)
						)
						(arc
							(start -0.2032 -0.3048)
							(mid -0.275042 -0.275042)
							(end -0.3048 -0.2032)
						)
						(arc
							(start -0.3048 0.2032)
							(mid -0.275042 0.275042)
							(end -0.2032 0.3048)
						)
						(arc
							(start 0.2032 0.3048)
							(mid 0.275042 0.275042)
							(end 0.3048 0.2032)
						)
					)
					(width 0)
					(fill yes)
				)
			)
		)
	)
	(footprint ""
		(layer "F.Cu")
		(at 54.8894 -52.5018 90)
		(property "Reference" "R35"
			(at 0 0 90)
			(layer "F.SilkS")
			(hide yes)
			(effects
				(font
					(size 1.27 1.27)
				)
			)
		)
		(property "Value" "4K7R2F-GP"
			(at 0.064008 -4.679696 90)
			(unlocked yes)
			(layer "F.Fab")
			(hide yes)
			(effects
				(font
					(size 2.54 2.54)
					(thickness 0.381)
				)
			)
		)
		(property "Device Type" "R402H16"
			(at 0.064008 -6.203696 90)
			(unlocked yes)
			(layer "F.Fab")
			(hide yes)
			(effects
				(font
					(size 2.54 2.54)
					(thickness 0.381)
				)
			)
		)
		(duplicate_pad_numbers_are_jumpers no)
		(fp_line
			(start 0.508 -0.9398)
			(end -0.508 -0.9398)
			(stroke
				(width 0.1524)
				(type default)
			)
			(layer "F.SilkS")
		)
		(fp_line
			(start -0.508 -0.9398)
			(end -0.508 0.9398)
			(stroke
				(width 0.1524)
				(type default)
			)
			(layer "F.SilkS")
		)
		(fp_rect
			(start -0.508 0.9398)
			(end 0.508 -0.9398)
			(stroke
				(width 0)
				(type default)
			)
			(fill no)
			(layer "F.CrtYd")
		)
		(fp_rect
			(start -0.508 0.9398)
			(end 0.508 -0.9398)
			(stroke
				(width 0)
				(type default)
			)
			(fill no)
			(layer "F.Fab")
		)
		(pad "1" smd custom
			(at 0 -0.4445 90)
			(size 0.1397 0.1397)
			(layers "F.Cu" "F.Mask" "F.Paste")
			(net "P3V3_STBY_B")
			(options
				(clearance outline)
				(anchor circle)
			)
			(primitives
				(gr_poly
					(pts
						(arc
							(start -0.1778 -0.2794)
							(mid -0.249642 -0.249642)
							(end -0.2794 -0.1778)
						)
						(arc
							(start -0.2794 0.1778)
							(mid -0.249642 0.249642)
							(end -0.1778 0.2794)
						)
						(arc
							(start 0.1778 0.2794)
							(mid 0.249642 0.249642)
							(end 0.2794 0.1778)
						)
						(arc
							(start 0.2794 -0.1778)
							(mid 0.249642 -0.249642)
							(end 0.1778 -0.2794)
						)
					)
					(width 0)
					(fill yes)
				)
			)
		)
		(pad "2" smd custom
			(at 0 0.4445 90)
			(size 0.1397 0.1397)
			(layers "F.Cu" "F.Mask" "F.Paste")
			(net "TEMP_2_A0")
			(options
				(clearance outline)
				(anchor circle)
			)
			(primitives
				(gr_poly
					(pts
						(arc
							(start -0.1778 -0.2794)
							(mid -0.249642 -0.249642)
							(end -0.2794 -0.1778)
						)
						(arc
							(start -0.2794 0.1778)
							(mid -0.249642 0.249642)
							(end -0.1778 0.2794)
						)
						(arc
							(start 0.1778 0.2794)
							(mid 0.249642 0.249642)
							(end 0.2794 0.1778)
						)
						(arc
							(start 0.2794 -0.1778)
							(mid 0.249642 -0.249642)
							(end 0.1778 -0.2794)
						)
					)
					(width 0)
					(fill yes)
				)
			)
		)
	)
	(footprint ""
		(layer "F.Cu")
		(at 56.063642 -73.56983 180)
		(property "Reference" "R18"
			(at 0 0 180)
			(layer "F.SilkS")
			(hide yes)
			(effects
				(font
					(size 1.27 1.27)
				)
			)
		)
		(property "Value" "200R2J-L1-GP"
			(at 0.064008 -4.679696 180)
			(unlocked yes)
			(layer "F.Fab")
			(hide yes)
			(effects
				(font
					(size 2.54 2.54)
					(thickness 0.381)
				)
			)
		)
		(property "Device Type" "R402H16"
			(at 0.064008 -6.203696 180)
			(unlocked yes)
			(layer "F.Fab")
			(hide yes)
			(effects
				(font
					(size 2.54 2.54)
					(thickness 0.381)
				)
			)
		)
		(duplicate_pad_numbers_are_jumpers no)
		(fp_line
			(start 0.508 -0.9398)
			(end -0.508 -0.9398)
			(stroke
				(width 0.1524)
				(type default)
			)
			(layer "F.SilkS")
		)
		(fp_line
			(start -0.508 -0.9398)
			(end -0.508 0.9398)
			(stroke
				(width 0.1524)
				(type default)
			)
			(layer "F.SilkS")
		)
		(fp_rect
			(start -0.508 0.9398)
			(end 0.508 -0.9398)
			(stroke
				(width 0)
				(type default)
			)
			(fill no)
			(layer "F.CrtYd")
		)
		(fp_rect
			(start -0.508 0.9398)
			(end 0.508 -0.9398)
			(stroke
				(width 0)
				(type default)
			)
			(fill no)
			(layer "F.Fab")
		)
		(pad "1" smd custom
			(at 0 -0.4445 180)
			(size 0.1397 0.1397)
			(layers "F.Cu" "F.Mask" "F.Paste")
			(net "P5V_USB_B")
			(options
				(clearance outline)
				(anchor circle)
			)
			(primitives
				(gr_poly
					(pts
						(arc
							(start -0.1778 -0.2794)
							(mid -0.249642 -0.249642)
							(end -0.2794 -0.1778)
						)
						(arc
							(start -0.2794 0.1778)
							(mid -0.249642 0.249642)
							(end -0.1778 0.2794)
						)
						(arc
							(start 0.1778 0.2794)
							(mid 0.249642 0.249642)
							(end 0.2794 0.1778)
						)
						(arc
							(start 0.2794 -0.1778)
							(mid 0.249642 -0.249642)
							(end 0.1778 -0.2794)
						)
					)
					(width 0)
					(fill yes)
				)
			)
		)
		(pad "2" smd custom
			(at 0 0.4445 180)
			(size 0.1397 0.1397)
			(layers "F.Cu" "F.Mask" "F.Paste")
			(net "PWR_BTN_LED_B_R")
			(options
				(clearance outline)
				(anchor circle)
			)
			(primitives
				(gr_poly
					(pts
						(arc
							(start -0.1778 -0.2794)
							(mid -0.249642 -0.249642)
							(end -0.2794 -0.1778)
						)
						(arc
							(start -0.2794 0.1778)
							(mid -0.249642 0.249642)
							(end -0.1778 0.2794)
						)
						(arc
							(start 0.1778 0.2794)
							(mid 0.249642 0.249642)
							(end 0.2794 0.1778)
						)
						(arc
							(start 0.2794 -0.1778)
							(mid 0.249642 -0.249642)
							(end 0.1778 -0.2794)
						)
					)
					(width 0)
					(fill yes)
				)
			)
		)
	)
	(footprint ""
		(layer "F.Cu")
		(at 12.907772 -50.643536 90)
		(property "Reference" "C14"
			(at 0 0 90)
			(layer "F.SilkS")
			(hide yes)
			(effects
				(font
					(size 1.27 1.27)
				)
			)
		)
		(property "Value" "SCD1U16V2KX-3GP"
			(at 1.1811 -3.3909 90)
			(unlocked yes)
			(layer "F.Fab")
			(hide yes)
			(effects
				(font
					(size 2.54 2.54)
					(thickness 0.381)
				)
			)
		)
		(property "Device Type" "C402H22"
			(at 1.1811 -4.9149 90)
			(unlocked yes)
			(layer "F.Fab")
			(hide yes)
			(effects
				(font
					(size 2.54 2.54)
					(thickness 0.381)
				)
			)
		)
		(duplicate_pad_numbers_are_jumpers no)
		(fp_rect
			(start -0.4318 0.9525)
			(end 0.4318 -0.9525)
			(stroke
				(width 0)
				(type default)
			)
			(fill no)
			(layer "F.CrtYd")
		)
		(fp_rect
			(start -0.4318 0.9525)
			(end 0.4318 -0.9525)
			(stroke
				(width 0)
				(type default)
			)
			(fill no)
			(layer "F.Fab")
		)
		(pad "1" smd custom
			(at 0 -0.4445 90)
			(size 0.1524 0.1524)
			(layers "F.Cu" "F.Mask" "F.Paste")
			(net "P3V3_STBY_A")
			(options
				(clearance outline)
				(anchor circle)
			)
			(primitives
				(gr_poly
					(pts
						(arc
							(start 0.3048 -0.2032)
							(mid 0.275042 -0.275042)
							(end 0.2032 -0.3048)
						)
						(arc
							(start -0.2032 -0.3048)
							(mid -0.275042 -0.275042)
							(end -0.3048 -0.2032)
						)
						(arc
							(start -0.3048 0.2032)
							(mid -0.275042 0.275042)
							(end -0.2032 0.3048)
						)
						(arc
							(start 0.2032 0.3048)
							(mid 0.275042 0.275042)
							(end 0.3048 0.2032)
						)
					)
					(width 0)
					(fill yes)
				)
			)
		)
		(pad "2" smd custom
			(at 0 0.4445 90)
			(size 0.1524 0.1524)
			(layers "F.Cu" "F.Mask" "F.Paste")
			(net "GND")
			(options
				(clearance outline)
				(anchor circle)
			)
			(primitives
				(gr_poly
					(pts
						(arc
							(start 0.3048 -0.2032)
							(mid 0.275042 -0.275042)
							(end 0.2032 -0.3048)
						)
						(arc
							(start -0.2032 -0.3048)
							(mid -0.275042 -0.275042)
							(end -0.3048 -0.2032)
						)
						(arc
							(start -0.3048 0.2032)
							(mid -0.275042 0.275042)
							(end -0.2032 0.3048)
						)
						(arc
							(start 0.2032 0.3048)
							(mid 0.275042 0.275042)
							(end 0.3048 0.2032)
						)
					)
					(width 0)
					(fill yes)
				)
			)
		)
	)
	(footprint ""
		(layer "F.Cu")
		(at 54.8132 -26.87574)
		(property "Reference" "C28"
			(at 0 0 0)
			(layer "F.SilkS")
			(hide yes)
			(effects
				(font
					(size 1.27 1.27)
				)
			)
		)
		(property "Value" "SCD1U16V2KX-3GP"
			(at 1.1811 -2.7051 0)
			(unlocked yes)
			(layer "F.Fab")
			(hide yes)
			(effects
				(font
					(size 1.016 1.016)
					(thickness 0.1524)
				)
			)
		)
		(property "Device Type" "C402H22"
			(at 1.1811 -4.2291 0)
			(unlocked yes)
			(layer "F.Fab")
			(hide yes)
			(effects
				(font
					(size 1.016 1.016)
					(thickness 0.1524)
				)
			)
		)
		(duplicate_pad_numbers_are_jumpers no)
		(fp_rect
			(start -0.4318 0.9525)
			(end 0.4318 -0.9525)
			(stroke
				(width 0)
				(type default)
			)
			(fill no)
			(layer "F.CrtYd")
		)
		(fp_rect
			(start -0.4318 0.9525)
			(end 0.4318 -0.9525)
			(stroke
				(width 0)
				(type default)
			)
			(fill no)
			(layer "F.Fab")
		)
		(pad "1" smd custom
			(at 0 -0.4445)
			(size 0.1524 0.1524)
			(layers "F.Cu" "F.Mask" "F.Paste")
			(net "P3V3_STBY_B")
			(options
				(clearance outline)
				(anchor circle)
			)
			(primitives
				(gr_poly
					(pts
						(arc
							(start 0.3048 -0.2032)
							(mid 0.275042 -0.275042)
							(end 0.2032 -0.3048)
						)
						(arc
							(start -0.2032 -0.3048)
							(mid -0.275042 -0.275042)
							(end -0.3048 -0.2032)
						)
						(arc
							(start -0.3048 0.2032)
							(mid -0.275042 0.275042)
							(end -0.2032 0.3048)
						)
						(arc
							(start 0.2032 0.3048)
							(mid 0.275042 0.275042)
							(end 0.3048 0.2032)
						)
					)
					(width 0)
					(fill yes)
				)
			)
		)
		(pad "2" smd custom
			(at 0 0.4445)
			(size 0.1524 0.1524)
			(layers "F.Cu" "F.Mask" "F.Paste")
			(net "GND")
			(options
				(clearance outline)
				(anchor circle)
			)
			(primitives
				(gr_poly
					(pts
						(arc
							(start 0.3048 -0.2032)
							(mid 0.275042 -0.275042)
							(end 0.2032 -0.3048)
						)
						(arc
							(start -0.2032 -0.3048)
							(mid -0.275042 -0.275042)
							(end -0.3048 -0.2032)
						)
						(arc
							(start -0.3048 0.2032)
							(mid -0.275042 0.275042)
							(end -0.2032 0.3048)
						)
						(arc
							(start 0.2032 0.3048)
							(mid 0.275042 0.275042)
							(end 0.3048 0.2032)
						)
					)
					(width 0)
					(fill yes)
				)
			)
		)
	)
)
